(kicad_sch (version 20230121) (generator eeschema)

  (paper "A3")

  (title_block
    (title "Kria K26 Devboard")
    (date "2024-03-26")
    (rev "1.2.5")
    (comment 1 "www.antmicro.com")
    (comment 2 "Antmicro Ltd.")
  )

  (junction (at 183.515 57.15) (diameter 0) (color 0 0 0 0)
  )
  (junction (at 114.3 102.87) (diameter 0) (color 0 0 0 0)
  )
  (junction (at 130.175 57.15) (diameter 0) (color 0 0 0 0)
  )
  (junction (at 169.545 66.04) (diameter 0) (color 0 0 0 0)
  )
  (junction (at 127 57.15) (diameter 0) (color 0 0 0 0)
  )
  (junction (at 180.34 72.39) (diameter 0) (color 0 0 0 0)
  )
  (junction (at 113.03 100.33) (diameter 0) (color 0 0 0 0)
  )
  (junction (at 158.75 57.15) (diameter 0) (color 0 0 0 0)
  )
  (junction (at 144.145 57.15) (diameter 0) (color 0 0 0 0)
  )

  (no_connect (at 139.7 111.76))
  (no_connect (at 111.76 113.03))
  (no_connect (at 111.76 115.57))
  (no_connect (at 139.7 95.25))

  (bus_entry (at 170.18 90.17) (size -2.54 2.54)
    (stroke (width 0) (type default))
  )
  (bus_entry (at 170.18 95.25) (size -2.54 2.54)
    (stroke (width 0) (type default))
  )

  (wire (pts (xy 127 57.15) (xy 127 87.63))
    (stroke (width 0) (type default))
  )
  (wire (pts (xy 132.08 100.33) (xy 132.08 109.22))
    (stroke (width 0) (type default))
  )
  (wire (pts (xy 178.435 57.15) (xy 183.515 57.15))
    (stroke (width 0) (type default))
  )
  (wire (pts (xy 156.845 95.25) (xy 156.845 99.06))
    (stroke (width 0) (type default))
  )
  (wire (pts (xy 154.94 97.79) (xy 167.64 97.79))
    (stroke (width 0) (type default))
  )
  (wire (pts (xy 165.735 109.22) (xy 165.735 110.49))
    (stroke (width 0) (type default))
  )
  (wire (pts (xy 158.75 64.135) (xy 158.75 66.04))
    (stroke (width 0) (type default))
  )
  (bus (pts (xy 170.18 90.17) (xy 170.18 95.25))
    (stroke (width 0) (type default))
  )

  (wire (pts (xy 133.35 95.25) (xy 133.35 97.79))
    (stroke (width 0) (type default))
  )
  (wire (pts (xy 183.515 55.245) (xy 183.515 57.15))
    (stroke (width 0) (type default))
  )
  (wire (pts (xy 111.76 87.63) (xy 127 87.63))
    (stroke (width 0) (type default))
  )
  (wire (pts (xy 158.75 57.15) (xy 165.735 57.15))
    (stroke (width 0) (type default))
  )
  (wire (pts (xy 116.84 120.65) (xy 116.84 128.905))
    (stroke (width 0) (type default))
  )
  (wire (pts (xy 165.735 113.03) (xy 168.275 113.03))
    (stroke (width 0) (type default))
  )
  (wire (pts (xy 169.545 66.04) (xy 169.545 67.31))
    (stroke (width 0) (type default))
  )
  (wire (pts (xy 180.34 72.39) (xy 186.436 72.39))
    (stroke (width 0) (type default))
  )
  (wire (pts (xy 127 57.15) (xy 130.175 57.15))
    (stroke (width 0) (type default))
  )
  (wire (pts (xy 111.76 128.905) (xy 113.665 128.905))
    (stroke (width 0) (type default))
  )
  (wire (pts (xy 158.75 66.04) (xy 169.545 66.04))
    (stroke (width 0) (type default))
  )
  (wire (pts (xy 156.845 95.25) (xy 154.94 95.25))
    (stroke (width 0) (type default))
  )
  (wire (pts (xy 154.94 92.71) (xy 167.64 92.71))
    (stroke (width 0) (type default))
  )
  (wire (pts (xy 158.75 59.055) (xy 158.75 57.15))
    (stroke (width 0) (type default))
  )
  (wire (pts (xy 111.76 95.25) (xy 133.35 95.25))
    (stroke (width 0) (type default))
  )
  (wire (pts (xy 132.08 109.22) (xy 139.7 109.22))
    (stroke (width 0) (type default))
  )
  (wire (pts (xy 113.665 128.905) (xy 113.665 123.19))
    (stroke (width 0) (type default))
  )
  (wire (pts (xy 156.845 111.76) (xy 156.845 115.57))
    (stroke (width 0) (type default))
  )
  (wire (pts (xy 111.76 92.71) (xy 139.7 92.71))
    (stroke (width 0) (type default))
  )
  (wire (pts (xy 111.76 100.33) (xy 113.03 100.33))
    (stroke (width 0) (type default))
  )
  (wire (pts (xy 144.145 57.15) (xy 144.145 59.055))
    (stroke (width 0) (type default))
  )
  (wire (pts (xy 144.145 57.15) (xy 130.175 57.15))
    (stroke (width 0) (type default))
  )
  (wire (pts (xy 130.81 114.3) (xy 139.7 114.3))
    (stroke (width 0) (type default))
  )
  (wire (pts (xy 144.145 57.15) (xy 158.75 57.15))
    (stroke (width 0) (type default))
  )
  (wire (pts (xy 133.35 97.79) (xy 139.7 97.79))
    (stroke (width 0) (type default))
  )
  (wire (pts (xy 113.665 123.19) (xy 111.76 123.19))
    (stroke (width 0) (type default))
  )
  (wire (pts (xy 169.545 66.04) (xy 169.545 64.77))
    (stroke (width 0) (type default))
  )
  (wire (pts (xy 180.34 70.485) (xy 180.34 72.39))
    (stroke (width 0) (type default))
  )
  (wire (pts (xy 111.76 102.87) (xy 114.3 102.87))
    (stroke (width 0) (type default))
  )
  (wire (pts (xy 111.76 107.95) (xy 114.3 107.95))
    (stroke (width 0) (type default))
  )
  (wire (pts (xy 113.03 105.41) (xy 113.03 100.33))
    (stroke (width 0) (type default))
  )
  (wire (pts (xy 130.81 102.87) (xy 130.81 114.3))
    (stroke (width 0) (type default))
  )
  (bus (pts (xy 170.18 87.63) (xy 170.18 90.17))
    (stroke (width 0) (type default))
  )

  (wire (pts (xy 116.84 120.65) (xy 111.76 120.65))
    (stroke (width 0) (type default))
  )
  (wire (pts (xy 113.03 100.33) (xy 132.08 100.33))
    (stroke (width 0) (type default))
  )
  (wire (pts (xy 127 57.15) (xy 124.206 57.15))
    (stroke (width 0) (type default))
  )
  (wire (pts (xy 114.3 102.87) (xy 130.81 102.87))
    (stroke (width 0) (type default))
  )
  (wire (pts (xy 111.76 105.41) (xy 113.03 105.41))
    (stroke (width 0) (type default))
  )
  (wire (pts (xy 154.94 114.3) (xy 165.735 114.3))
    (stroke (width 0) (type default))
  )
  (wire (pts (xy 114.3 107.95) (xy 114.3 102.87))
    (stroke (width 0) (type default))
  )
  (wire (pts (xy 177.165 72.39) (xy 180.34 72.39))
    (stroke (width 0) (type default))
  )
  (wire (pts (xy 156.845 111.76) (xy 154.94 111.76))
    (stroke (width 0) (type default))
  )
  (wire (pts (xy 165.735 110.49) (xy 168.275 110.49))
    (stroke (width 0) (type default))
  )
  (wire (pts (xy 154.94 109.22) (xy 165.735 109.22))
    (stroke (width 0) (type default))
  )
  (wire (pts (xy 165.735 114.3) (xy 165.735 113.03))
    (stroke (width 0) (type default))
  )
  (wire (pts (xy 183.515 57.15) (xy 186.436 57.15))
    (stroke (width 0) (type default))
  )
  (wire (pts (xy 130.175 57.15) (xy 130.175 62.865))
    (stroke (width 0) (type default))
  )
  (bus (pts (xy 173.99 87.63) (xy 170.18 87.63))
    (stroke (width 0) (type default))
  )

  (wire (pts (xy 130.175 67.945) (xy 130.175 71.755))
    (stroke (width 0) (type default))
  )

  (label "USBC_TVS_P" (at 114.3 100.33 0) (fields_autoplaced)
    (effects (font (size 1.27 1.27)) (justify left bottom))
  )
  (label "USBC_CC1" (at 167.64 92.71 180) (fields_autoplaced)
    (effects (font (size 1.27 1.27)) (justify right bottom))
  )
  (label "USBC_TVS_CC2" (at 128.27 95.25 180) (fields_autoplaced)
    (effects (font (size 1.27 1.27)) (justify right bottom))
  )
  (label "USBC_CC2" (at 167.64 97.79 180) (fields_autoplaced)
    (effects (font (size 1.27 1.27)) (justify right bottom))
  )
  (label "USBC_TVS_CC1" (at 128.27 92.71 180) (fields_autoplaced)
    (effects (font (size 1.27 1.27)) (justify right bottom))
  )
  (label "USBC_TVS_N" (at 114.3 102.87 0) (fields_autoplaced)
    (effects (font (size 1.27 1.27)) (justify left bottom))
  )

  (global_label "SH_UP" (shape input) (at 111.76 128.905 180) (fields_autoplaced)
    (effects (font (size 1.27 1.27)) (justify right))
    (property "Intersheetrefs" "${INTERSHEET_REFS}" (at 103.3277 128.9844 0)
      (effects (font (size 1.27 1.27)) (justify right) hide)
    )
  )

  (hierarchical_label "PD_VBUS" (shape input) (at 186.436 57.15 0) (fields_autoplaced)
    (effects (font (size 1.27 1.27)) (justify left))
  )
  (hierarchical_label "USBC_VBUS" (shape output) (at 124.206 57.15 180) (fields_autoplaced)
    (effects (font (size 1.27 1.27)) (justify right))
  )
  (hierarchical_label "USBC_N" (shape input) (at 168.275 113.03 0) (fields_autoplaced)
    (effects (font (size 1.27 1.27)) (justify left))
  )
  (hierarchical_label "USBC_CC[1..2]" (shape input) (at 173.99 87.63 0) (fields_autoplaced)
    (effects (font (size 1.27 1.27)) (justify left))
  )
  (hierarchical_label "PD_EN" (shape input) (at 186.436 72.39 0) (fields_autoplaced)
    (effects (font (size 1.27 1.27)) (justify left))
  )
  (hierarchical_label "USBC_P" (shape input) (at 168.275 110.49 0) (fields_autoplaced)
    (effects (font (size 1.27 1.27)) (justify left))
  )

  (symbol (lib_id "kria-k26-devboard:SMF4L15CA") (at 144.145 59.055 270) (unit 1)
    (in_bom yes) (on_board yes) (dnp no) (fields_autoplaced)
    (property "Reference" "D26" (at 146.685 64.1349 90)
      (effects (font (size 1.27 1.27)) (justify left))
    )
    (property "Value" "SMF4L15CA" (at 146.177 66.6749 90)
      (effects (font (size 1.27 1.27) (thickness 0.15)) (justify left) hide)
    )
    (property "Footprint" "kria-k26-devboard-footprints:SOD-123FL" (at 144.145 59.055 0)
      (effects (font (size 1.27 1.27) (thickness 0.15)) (justify left bottom) hide)
    )
    (property "Datasheet" "https://www.mouser.pl/datasheet/2/240/Littelfuse_TVS_Diode_SMF4L_Datasheet_pdf-1665786.pdf" (at 144.145 59.055 0)
      (effects (font (size 1.27 1.27) (thickness 0.15)) (justify left bottom) hide)
    )
    (property "MPN" "SMF4L15CA" (at 146.685 66.6749 90)
      (effects (font (size 1.27 1.27) (thickness 0.15)) (justify left))
    )
    (property "Manufacturer" "Infineon Technologies" (at 144.145 59.055 0)
      (effects (font (size 1.27 1.27) (thickness 0.15)) (justify left bottom) hide)
    )
    (property "Author" "Antmicro" (at 123.825 85.725 0)
      (effects (font (size 1.27 1.27) (thickness 0.15)) (justify left bottom) hide)
    )
    (property "License" "Apache-2.0" (at 121.285 85.725 0)
      (effects (font (size 1.27 1.27) (thickness 0.15)) (justify left bottom) hide)
    )
    (pin "1")
    (pin "2")
    (instances
      (project "kria-k26-devboard"
        (path ""
          (reference "D26") (unit 1)
        )
      )
    )
  )

  (symbol (lib_id "kria-k26-devboard:GND") (at 116.84 128.905 0) (unit 1)
    (in_bom yes) (on_board yes) (dnp no) (fields_autoplaced)
    (property "Reference" "#PWR0391" (at 116.84 135.255 0)
      (effects (font (size 1.27 1.27)) hide)
    )
    (property "Value" "GND" (at 116.84 133.35 0)
      (effects (font (size 1.27 1.27)))
    )
    (property "Footprint" "" (at 125.73 136.525 0)
      (effects (font (size 1.27 1.27) (thickness 0.15)) (justify left bottom) hide)
    )
    (property "Datasheet" "" (at 125.73 141.605 0)
      (effects (font (size 1.27 1.27) (thickness 0.15)) (justify left bottom) hide)
    )
    (property "Author" "Antmicro" (at 125.73 136.525 0)
      (effects (font (size 1.27 1.27) (thickness 0.15)) (justify left bottom) hide)
    )
    (property "License" "Apache-2.0" (at 125.73 139.065 0)
      (effects (font (size 1.27 1.27) (thickness 0.15)) (justify left bottom) hide)
    )
    (pin "1")
    (instances
      (project "kria-k26-devboard"
        (path ""
          (reference "#PWR0391") (unit 1)
        )
      )
    )
  )

  (symbol (lib_id "kria-k26-devboard:USB-C_GCT_USB4105-GF-A") (at 111.76 87.63 0) (unit 1)
    (in_bom yes) (on_board yes) (dnp no) (fields_autoplaced)
    (property "Reference" "J10" (at 98.425 80.01 0)
      (effects (font (size 1.27 1.27)))
    )
    (property "Value" "USB-C_GCT_USB4105-GF-A" (at 122.2375 81.915 0)
      (effects (font (size 1.27 1.27) (thickness 0.15)) hide)
    )
    (property "Footprint" "kria-k26-devboard-footprints:USB-C_Receptacle_GCT_USB4105-GF-A" (at 95.25 81.28 0)
      (effects (font (size 1.27 1.27) (thickness 0.15)) (justify left bottom) hide)
    )
    (property "Datasheet" "https://gct.co/files/drawings/usb4105.pdf" (at 111.76 87.63 0)
      (effects (font (size 1.27 1.27) (thickness 0.15)) (justify left bottom) hide)
    )
    (property "Manufacturer" "GCT" (at 95.25 78.74 0)
      (effects (font (size 1.27 1.27) (thickness 0.15)) (justify left bottom) hide)
    )
    (property "MPN" "USB4105-GF-A" (at 98.425 82.55 0)
      (effects (font (size 1.27 1.27) (thickness 0.15)))
    )
    (property "Author" "Antmicro" (at 149.86 105.41 0)
      (effects (font (size 1.27 1.27) (thickness 0.15)) (justify left bottom) hide)
    )
    (property "License" "Apache-2.0" (at 149.86 107.95 0)
      (effects (font (size 1.27 1.27) (thickness 0.15)) (justify left bottom) hide)
    )
    (property "VSD_Class" "USB-C" (at 149.86 110.49 0)
      (effects (font (size 1.27 1.27)) (justify left bottom) hide)
    )
    (pin "A1")
    (pin "A12")
    (pin "A4")
    (pin "A5")
    (pin "A6")
    (pin "A7")
    (pin "A8")
    (pin "A9")
    (pin "B1")
    (pin "B12")
    (pin "B4")
    (pin "B5")
    (pin "B6")
    (pin "B7")
    (pin "B8")
    (pin "B9")
    (pin "SH")
    (instances
      (project "kria-k26-devboard"
        (path ""
          (reference "J10") (unit 1)
        )
      )
    )
  )

  (symbol (lib_id "kria-k26-devboard:GND") (at 144.145 71.755 0) (unit 1)
    (in_bom yes) (on_board yes) (dnp no) (fields_autoplaced)
    (property "Reference" "#PWR0392" (at 144.145 78.105 0)
      (effects (font (size 1.27 1.27)) hide)
    )
    (property "Value" "GND" (at 144.145 76.835 0)
      (effects (font (size 1.27 1.27)))
    )
    (property "Footprint" "" (at 153.035 79.375 0)
      (effects (font (size 1.27 1.27) (thickness 0.15)) (justify left bottom) hide)
    )
    (property "Datasheet" "" (at 153.035 84.455 0)
      (effects (font (size 1.27 1.27) (thickness 0.15)) (justify left bottom) hide)
    )
    (property "Author" "Antmicro" (at 153.035 79.375 0)
      (effects (font (size 1.27 1.27) (thickness 0.15)) (justify left bottom) hide)
    )
    (property "License" "Apache-2.0" (at 153.035 81.915 0)
      (effects (font (size 1.27 1.27) (thickness 0.15)) (justify left bottom) hide)
    )
    (pin "1")
    (instances
      (project "kria-k26-devboard"
        (path ""
          (reference "#PWR0392") (unit 1)
        )
      )
    )
  )

  (symbol (lib_id "kria-k26-devboard:C_100n_50V_0402") (at 130.175 62.865 270) (unit 1)
    (in_bom yes) (on_board yes) (dnp no) (fields_autoplaced)
    (property "Reference" "C231" (at 132.715 64.1412 90)
      (effects (font (size 1.27 1.27)) (justify left))
    )
    (property "Value" "C_100n_50V_0402" (at 130.175 62.865 0)
      (effects (font (size 1.27 1.27) (thickness 0.15)) (justify left bottom) hide)
    )
    (property "Footprint" "kria-k26-devboard-footprints:C_0402_1005Metric" (at 130.175 62.865 0)
      (effects (font (size 1.27 1.27) (thickness 0.15)) (justify left bottom) hide)
    )
    (property "Datasheet" " " (at 130.175 62.865 0)
      (effects (font (size 1.27 1.27) (thickness 0.15)) (justify left bottom) hide)
    )
    (property "MPN" "GRM155R71H104KE14D" (at 130.175 62.865 0)
      (effects (font (size 1.27 1.27) (thickness 0.15)) (justify left bottom) hide)
    )
    (property "Manufacturer" "Murata" (at 130.175 62.865 0)
      (effects (font (size 1.27 1.27) (thickness 0.15)) (justify left bottom) hide)
    )
    (property "Val" "100n/50V" (at 132.715 66.6812 90)
      (effects (font (size 1.27 1.27) (thickness 0.15)) (justify left))
    )
    (property "License" "Apache-2.0" (at 107.315 83.185 0)
      (effects (font (size 1.27 1.27) (thickness 0.15)) (justify left bottom) hide)
    )
    (property "Author" "Antmicro" (at 104.775 83.185 0)
      (effects (font (size 1.27 1.27) (thickness 0.15)) (justify left bottom) hide)
    )
    (property "Voltage" "" (at 102.235 83.185 0)
      (effects (font (size 1.27 1.27)) (justify left bottom) hide)
    )
    (property "Dielectric" "" (at 99.695 83.185 0)
      (effects (font (size 1.27 1.27)) (justify left bottom) hide)
    )
    (pin "1")
    (pin "2")
    (instances
      (project "kria-k26-devboard"
        (path ""
          (reference "C231") (unit 1)
        )
      )
    )
  )

  (symbol (lib_id "kria-k26-devboard:82400152") (at 154.94 114.3 180) (unit 1)
    (in_bom yes) (on_board yes) (dnp no) (fields_autoplaced)
    (property "Reference" "U60" (at 147.32 102.87 0)
      (effects (font (size 1.27 1.27)))
    )
    (property "Value" "82400152" (at 147.32 105.41 0)
      (effects (font (size 1.27 1.27) (thickness 0.15)))
    )
    (property "Footprint" "kria-k26-devboard-footprints:SOT-563" (at 154.94 109.22 0)
      (effects (font (size 1.27 1.27) (thickness 0.15)) (justify left bottom) hide)
    )
    (property "Datasheet" "https://www.we-online.com/components/products/datasheet/82400152.pdf" (at 154.94 107.95 0)
      (effects (font (size 1.27 1.27) (thickness 0.15)) (justify left bottom) hide)
    )
    (property "MPN" "82400152" (at 163.83 104.14 0)
      (effects (font (size 1.27 1.27) (thickness 0.15)) (justify left bottom) hide)
    )
    (property "Manufacturer" "Würth Elektronik" (at 161.29 106.68 0)
      (effects (font (size 1.27 1.27) (thickness 0.15)) (justify left bottom) hide)
    )
    (property "Author" "Antmicro" (at 124.46 93.98 0)
      (effects (font (size 1.27 1.27) (thickness 0.15)) (justify left bottom) hide)
    )
    (property "License" "Apache-2.0" (at 124.46 91.44 0)
      (effects (font (size 1.27 1.27) (thickness 0.15)) (justify left bottom) hide)
    )
    (pin "1")
    (pin "2")
    (pin "3")
    (pin "4")
    (pin "5")
    (pin "6")
    (instances
      (project "kria-k26-devboard"
        (path ""
          (reference "U60") (unit 1)
        )
      )
    )
  )

  (symbol (lib_id "kria-k26-devboard:DTC014T_SOT-416") (at 177.165 72.39 0) (mirror y) (unit 1)
    (in_bom yes) (on_board yes) (dnp no) (fields_autoplaced)
    (property "Reference" "Q17" (at 166.37 71.1199 0)
      (effects (font (size 1.27 1.27)) (justify left))
    )
    (property "Value" "DTC014T_SOT-416" (at 167.259 73.6599 0)
      (effects (font (size 1.27 1.27) (thickness 0.15)) (justify left) hide)
    )
    (property "Footprint" "kria-k26-devboard-footprints:SOT-416" (at 172.085 80.01 0)
      (effects (font (size 1.27 1.27) (thickness 0.15)) (justify left bottom) hide)
    )
    (property "Datasheet" "https://www.rohm.com/datasheet?p=DTC014TEB&dist=Mouser&media=referral&source=mouser.com&campaign=Mouser" (at 177.165 72.39 0)
      (effects (font (size 1.27 1.27) (thickness 0.15)) (justify left bottom) hide)
    )
    (property "Manufacturer" "ROHM Semiconductor" (at 161.925 74.93 0)
      (effects (font (size 1.27 1.27) (thickness 0.15)) (justify left bottom) hide)
    )
    (property "MPN" "DTC014TEBTL" (at 166.37 73.6599 0)
      (effects (font (size 1.27 1.27) (thickness 0.15)) (justify left))
    )
    (property "Author" "Antmicro" (at 151.765 92.71 0)
      (effects (font (size 1.27 1.27) (thickness 0.15)) (justify left bottom) hide)
    )
    (property "License" "Apache-2.0" (at 151.765 95.25 0)
      (effects (font (size 1.27 1.27) (thickness 0.15)) (justify left bottom) hide)
    )
    (pin "1")
    (pin "2")
    (pin "3")
    (instances
      (project "kria-k26-devboard"
        (path ""
          (reference "Q17") (unit 1)
        )
      )
    )
  )

  (symbol (lib_id "kria-k26-devboard:TP_0.75mm_SMD") (at 183.515 55.245 90) (unit 1)
    (in_bom yes) (on_board yes) (dnp no) (fields_autoplaced)
    (property "Reference" "TP44" (at 186.055 52.0699 90)
      (effects (font (size 1.27 1.27)) (justify right))
    )
    (property "Value" "TP_0.75mm_SMD" (at 186.055 55.245 0)
      (effects (font (size 1.27 1.27) (thickness 0.15)) (justify left bottom) hide)
    )
    (property "Footprint" "kria-k26-devboard-footprints:TP_SMD_0.75mm" (at 178.435 50.165 0)
      (effects (font (size 1.27 1.27) (thickness 0.15)) (justify left bottom) hide)
    )
    (property "Datasheet" "" (at 175.895 50.165 0)
      (effects (font (size 1.27 1.27) (thickness 0.15)) (justify left bottom) hide)
    )
    (property "MPN" "" (at 183.515 55.245 0)
      (effects (font (size 1.27 1.27) (thickness 0.15)) (justify left bottom) hide)
    )
    (property "Manufacturer" "" (at 183.515 55.245 0)
      (effects (font (size 1.27 1.27) (thickness 0.15)) (justify left bottom) hide)
    )
    (property "Author" "Antmicro" (at 198.755 40.005 0)
      (effects (font (size 1.27 1.27) (thickness 0.15)) (justify left bottom) hide)
    )
    (property "License" "Apache-2.0" (at 201.295 40.005 0)
      (effects (font (size 1.27 1.27) (thickness 0.15)) (justify left bottom) hide)
    )
    (pin "1")
    (instances
      (project "kria-k26-devboard"
        (path ""
          (reference "TP44") (unit 1)
        )
      )
    )
  )

  (symbol (lib_id "kria-k26-devboard:TP_0.75mm_SMD") (at 180.34 70.485 90) (unit 1)
    (in_bom yes) (on_board yes) (dnp no) (fields_autoplaced)
    (property "Reference" "TP45" (at 181.864 67.3099 90)
      (effects (font (size 1.27 1.27)) (justify right))
    )
    (property "Value" "TP_0.75mm_SMD" (at 182.88 70.485 0)
      (effects (font (size 1.27 1.27) (thickness 0.15)) (justify left bottom) hide)
    )
    (property "Footprint" "kria-k26-devboard-footprints:TP_SMD_0.75mm" (at 175.26 65.405 0)
      (effects (font (size 1.27 1.27) (thickness 0.15)) (justify left bottom) hide)
    )
    (property "Datasheet" "" (at 172.72 65.405 0)
      (effects (font (size 1.27 1.27) (thickness 0.15)) (justify left bottom) hide)
    )
    (property "MPN" "" (at 180.34 70.485 0)
      (effects (font (size 1.27 1.27) (thickness 0.15)) (justify left bottom) hide)
    )
    (property "Manufacturer" "" (at 180.34 70.485 0)
      (effects (font (size 1.27 1.27) (thickness 0.15)) (justify left bottom) hide)
    )
    (property "Author" "Antmicro" (at 195.58 55.245 0)
      (effects (font (size 1.27 1.27) (thickness 0.15)) (justify left bottom) hide)
    )
    (property "License" "Apache-2.0" (at 198.12 55.245 0)
      (effects (font (size 1.27 1.27) (thickness 0.15)) (justify left bottom) hide)
    )
    (pin "1")
    (instances
      (project "kria-k26-devboard"
        (path ""
          (reference "TP45") (unit 1)
        )
      )
    )
  )

  (symbol (lib_id "kria-k26-devboard:GND") (at 156.845 115.57 0) (mirror y) (unit 1)
    (in_bom yes) (on_board yes) (dnp no) (fields_autoplaced)
    (property "Reference" "#PWR0395" (at 156.845 121.92 0)
      (effects (font (size 1.27 1.27)) hide)
    )
    (property "Value" "GND" (at 156.845 120.65 0)
      (effects (font (size 1.27 1.27)))
    )
    (property "Footprint" "" (at 147.955 123.19 0)
      (effects (font (size 1.27 1.27) (thickness 0.15)) (justify left bottom) hide)
    )
    (property "Datasheet" "" (at 147.955 128.27 0)
      (effects (font (size 1.27 1.27) (thickness 0.15)) (justify left bottom) hide)
    )
    (property "Author" "Antmicro" (at 147.955 123.19 0)
      (effects (font (size 1.27 1.27) (thickness 0.15)) (justify left bottom) hide)
    )
    (property "License" "Apache-2.0" (at 147.955 125.73 0)
      (effects (font (size 1.27 1.27) (thickness 0.15)) (justify left bottom) hide)
    )
    (pin "1")
    (instances
      (project "kria-k26-devboard"
        (path ""
          (reference "#PWR0395") (unit 1)
        )
      )
    )
  )

  (symbol (lib_id "kria-k26-devboard:82400152") (at 154.94 97.79 180) (unit 1)
    (in_bom yes) (on_board yes) (dnp no) (fields_autoplaced)
    (property "Reference" "U59" (at 147.32 86.36 0)
      (effects (font (size 1.27 1.27)))
    )
    (property "Value" "82400152" (at 147.32 88.9 0)
      (effects (font (size 1.27 1.27) (thickness 0.15)))
    )
    (property "Footprint" "kria-k26-devboard-footprints:SOT-563" (at 154.94 92.71 0)
      (effects (font (size 1.27 1.27) (thickness 0.15)) (justify left bottom) hide)
    )
    (property "Datasheet" "https://www.we-online.com/components/products/datasheet/82400152.pdf" (at 154.94 91.44 0)
      (effects (font (size 1.27 1.27) (thickness 0.15)) (justify left bottom) hide)
    )
    (property "MPN" "82400152" (at 163.83 87.63 0)
      (effects (font (size 1.27 1.27) (thickness 0.15)) (justify left bottom) hide)
    )
    (property "Manufacturer" "Würth Elektronik" (at 161.29 90.17 0)
      (effects (font (size 1.27 1.27) (thickness 0.15)) (justify left bottom) hide)
    )
    (property "Author" "Antmicro" (at 124.46 77.47 0)
      (effects (font (size 1.27 1.27) (thickness 0.15)) (justify left bottom) hide)
    )
    (property "License" "Apache-2.0" (at 124.46 74.93 0)
      (effects (font (size 1.27 1.27) (thickness 0.15)) (justify left bottom) hide)
    )
    (pin "1")
    (pin "2")
    (pin "3")
    (pin "4")
    (pin "5")
    (pin "6")
    (instances
      (project "kria-k26-devboard"
        (path ""
          (reference "U59") (unit 1)
        )
      )
    )
  )

  (symbol (lib_id "kria-k26-devboard:GND") (at 156.845 99.06 0) (unit 1)
    (in_bom yes) (on_board yes) (dnp no) (fields_autoplaced)
    (property "Reference" "#PWR0393" (at 156.845 105.41 0)
      (effects (font (size 1.27 1.27)) hide)
    )
    (property "Value" "GND" (at 156.845 104.14 0)
      (effects (font (size 1.27 1.27)))
    )
    (property "Footprint" "" (at 165.735 106.68 0)
      (effects (font (size 1.27 1.27) (thickness 0.15)) (justify left bottom) hide)
    )
    (property "Datasheet" "" (at 165.735 111.76 0)
      (effects (font (size 1.27 1.27) (thickness 0.15)) (justify left bottom) hide)
    )
    (property "Author" "Antmicro" (at 165.735 106.68 0)
      (effects (font (size 1.27 1.27) (thickness 0.15)) (justify left bottom) hide)
    )
    (property "License" "Apache-2.0" (at 165.735 109.22 0)
      (effects (font (size 1.27 1.27) (thickness 0.15)) (justify left bottom) hide)
    )
    (pin "1")
    (instances
      (project "kria-k26-devboard"
        (path ""
          (reference "#PWR0393") (unit 1)
        )
      )
    )
  )

  (symbol (lib_id "kria-k26-devboard:PJA3441") (at 169.545 64.77 270) (mirror x) (unit 1)
    (in_bom yes) (on_board yes) (dnp no)
    (property "Reference" "Q16" (at 170.815 50.8 90)
      (effects (font (size 1.27 1.27)))
    )
    (property "Value" "PJA3441" (at 172.085 53.34 90)
      (effects (font (size 1.27 1.27) (thickness 0.15)) hide)
    )
    (property "Footprint" "kria-k26-devboard-footprints:SOT-23-3" (at 169.545 64.77 0)
      (effects (font (size 1.27 1.27) (thickness 0.15)) (justify left bottom) hide)
    )
    (property "Datasheet" "https://www.mouser.pl/datasheet/2/1057/PJA3441-1867252.pdf" (at 169.545 64.77 0)
      (effects (font (size 1.27 1.27) (thickness 0.15)) (justify left bottom) hide)
    )
    (property "Manufacturer" "Panjit" (at 173.355 57.15 0)
      (effects (font (size 1.27 1.27) (thickness 0.15)) (justify left bottom) hide)
    )
    (property "MPN" "PJA3441_R1_00001" (at 170.815 53.34 90)
      (effects (font (size 1.27 1.27) (thickness 0.15)))
    )
    (property "Author" "Antmicro" (at 147.955 40.64 0)
      (effects (font (size 1.27 1.27) (thickness 0.15)) (justify left bottom) hide)
    )
    (property "License" "Apache-2.0" (at 145.415 40.64 0)
      (effects (font (size 1.27 1.27) (thickness 0.15)) (justify left bottom) hide)
    )
    (pin "1")
    (pin "2")
    (pin "3")
    (instances
      (project "kria-k26-devboard"
        (path ""
          (reference "Q16") (unit 1)
        )
      )
    )
  )

  (symbol (lib_id "kria-k26-devboard:R_100k_0402") (at 158.75 59.055 270) (unit 1)
    (in_bom yes) (on_board yes) (dnp no) (fields_autoplaced)
    (property "Reference" "R149" (at 161.29 60.325 90)
      (effects (font (size 1.524 1.524)) (justify left))
    )
    (property "Value" "R_100k_0402" (at 154.94 59.055 0)
      (effects (font (size 1.27 1.27) (thickness 0.15)) (justify left bottom) hide)
    )
    (property "Footprint" "kria-k26-devboard-footprints:R_0402_1005Metric" (at 163.83 64.135 0)
      (effects (font (size 1.27 1.27) (thickness 0.15)) (justify left bottom) hide)
    )
    (property "Datasheet" "https://www.bourns.com/docs/product-datasheets/cr.pdf" (at 158.75 59.055 0)
      (effects (font (size 1.27 1.27) (thickness 0.15)) (justify left bottom) hide)
    )
    (property "Manufacturer" "Bourns" (at 168.91 64.135 0)
      (effects (font (size 1.27 1.27) (thickness 0.15)) (justify left bottom) hide)
    )
    (property "MPN" "CR0402-FX-1003GLF" (at 166.37 64.135 0)
      (effects (font (size 1.27 1.27) (thickness 0.15)) (justify left bottom) hide)
    )
    (property "Val" "100k" (at 161.29 63.4999 90)
      (effects (font (size 1.27 1.27) (thickness 0.15)) (justify left))
    )
    (property "License" "Apache-2.0" (at 133.35 79.375 0)
      (effects (font (size 1.27 1.27) (thickness 0.15)) (justify left bottom) hide)
    )
    (property "Author" "Antmicro" (at 130.81 79.375 0)
      (effects (font (size 1.27 1.27) (thickness 0.15)) (justify left bottom) hide)
    )
    (property "Tolerance" "1%" (at 148.59 79.375 0)
      (effects (font (size 1.27 1.27)) (justify left bottom) hide)
    )
    (pin "1")
    (pin "2")
    (instances
      (project "kria-k26-devboard"
        (path ""
          (reference "R149") (unit 1)
        )
      )
    )
  )

  (symbol (lib_id "kria-k26-devboard:GND") (at 169.545 77.47 0) (unit 1)
    (in_bom yes) (on_board yes) (dnp no) (fields_autoplaced)
    (property "Reference" "#PWR0394" (at 169.545 83.82 0)
      (effects (font (size 1.27 1.27)) hide)
    )
    (property "Value" "GND" (at 169.545 82.55 0)
      (effects (font (size 1.27 1.27)))
    )
    (property "Footprint" "" (at 178.435 85.09 0)
      (effects (font (size 1.27 1.27) (thickness 0.15)) (justify left bottom) hide)
    )
    (property "Datasheet" "" (at 178.435 90.17 0)
      (effects (font (size 1.27 1.27) (thickness 0.15)) (justify left bottom) hide)
    )
    (property "Author" "Antmicro" (at 178.435 85.09 0)
      (effects (font (size 1.27 1.27) (thickness 0.15)) (justify left bottom) hide)
    )
    (property "License" "Apache-2.0" (at 178.435 87.63 0)
      (effects (font (size 1.27 1.27) (thickness 0.15)) (justify left bottom) hide)
    )
    (pin "1")
    (instances
      (project "kria-k26-devboard"
        (path ""
          (reference "#PWR0394") (unit 1)
        )
      )
    )
  )

  (symbol (lib_id "kria-k26-devboard:GND") (at 130.175 71.755 0) (unit 1)
    (in_bom yes) (on_board yes) (dnp no) (fields_autoplaced)
    (property "Reference" "#PWR0103" (at 130.175 78.105 0)
      (effects (font (size 1.27 1.27)) hide)
    )
    (property "Value" "GND" (at 130.175 76.835 0)
      (effects (font (size 1.27 1.27)))
    )
    (property "Footprint" "" (at 139.065 79.375 0)
      (effects (font (size 1.27 1.27) (thickness 0.15)) (justify left bottom) hide)
    )
    (property "Datasheet" "" (at 139.065 84.455 0)
      (effects (font (size 1.27 1.27) (thickness 0.15)) (justify left bottom) hide)
    )
    (property "Author" "Antmicro" (at 139.065 79.375 0)
      (effects (font (size 1.27 1.27) (thickness 0.15)) (justify left bottom) hide)
    )
    (property "License" "Apache-2.0" (at 139.065 81.915 0)
      (effects (font (size 1.27 1.27) (thickness 0.15)) (justify left bottom) hide)
    )
    (pin "1")
    (instances
      (project "kria-k26-devboard"
        (path ""
          (reference "#PWR0103") (unit 1)
        )
      )
    )
  )
)
